# S9S_MB_2U (Grand Teton) — schematic netlist excerpt (pin names and nets, part order shuffled) for the footprints in the layout excerpt that follows; sources: Cadence DE-HDL packaged netlist, KiCad conversion of 03242023_DA0F0TMBIJ0_F0T_Motherboard_J_brd_V01_OCP.brd

C907  Q_CAP_DIFFBUS  DIFF BUS_0.22UF 6.3V 20% X6S  pkg C0201  page 173 : \1\ = P5E_CPU0_PE0_TX_C_DP<13> ; \2\ = P5E_CPU0_PE0_TX_DP<13>
R1487  Q_RES  100 1% CHIP  pkg 0402LF  page 183 : A = FM_PCH_SATA_RAID_KEY ; B = GND
R1300  Q_RES  33.2 1% CHIP  pkg 0402LF  page 205 : A = FM_BIOS_POST_CMPLT_N ; B = FM_BIOS_POST_CMPLT_BMC_N

(kicad_pcb
	(version 20260206)
	(generator "pcbnew")
	(generator_version "10.0")
	(general
		(thickness 1.6)
		(legacy_teardrops no)
	)
	(paper "A4")
	(title_block
		(title "03242023_DA0F0TMBIJ0_F0T_Motherboard_J_brd_V01_OCP.brd")
		(comment 1 "Grand Teton / footprints 3910-3912 of 6105")
	)
	(layers
		(0 "F.Cu" signal "TOP")
		(4 "In1.Cu" signal "GND")
		(6 "In2.Cu" signal "IN1")
		(8 "In3.Cu" signal "GND1")
		(10 "In4.Cu" signal "IN2")
		(12 "In5.Cu" signal "GND2")
		(14 "In6.Cu" signal "IN3")
		(16 "In7.Cu" signal "GND3")
		(18 "In8.Cu" signal "VCC")
		(20 "In9.Cu" signal "VCC1")
		(22 "In10.Cu" signal "GND4")
		(24 "In11.Cu" signal "IN4")
		(26 "In12.Cu" signal "GND5")
		(28 "In13.Cu" signal "IN5")
		(30 "In14.Cu" signal "GND6")
		(32 "In15.Cu" signal "IN6")
		(34 "In16.Cu" signal "GND7")
		(2 "B.Cu" signal "BOTTOM")
		(9 "F.Adhes" user "F.Adhesive")
		(11 "B.Adhes" user "B.Adhesive")
		(13 "F.Paste" user "Package Geometry/Pastemask Top")
		(15 "B.Paste" user "Package Geometry/Pastemask Bottom")
		(5 "F.SilkS" user "Ref Des/Silkscreen Top")
		(7 "B.SilkS" user "Ref Des/Silkscreen Bottom")
		(1 "F.Mask" user "Board Geometry/Soldermask Top")
		(3 "B.Mask" user "Board Geometry/Soldermask Bottom")
		(17 "Dwgs.User" user "User.Drawings")
		(19 "Cmts.User" user "User.Comments")
		(21 "Eco1.User" user "User.Eco1")
		(23 "Eco2.User" user "User.Eco2")
		(25 "Edge.Cuts" user "Board Geometry/Outline")
		(27 "Margin" user)
		(31 "F.CrtYd" user "Package Geometry/Place Bound Top")
		(29 "B.CrtYd" user "Package Geometry/Place Bound Bottom")
		(35 "F.Fab" user "Ref Des/Assembly Top")
		(33 "B.Fab" user "Ref Des/Assembly Bottom")
	)
	(footprint ""
		(layer "F.Cu")
		(at 307.363622 -41.900348 180)
		(property "Reference" "R1300"
			(at 0 0 180)
			(layer "F.SilkS")
			(hide yes)
			(effects
				(font
					(size 1.27 1.27)
				)
			)
		)
		(property "Value" ""
			(at 0 0 180)
			(layer "F.Fab")
			(effects
				(font
					(size 1.27 1.27)
				)
			)
		)
		(duplicate_pad_numbers_are_jumpers no)
		(fp_line
			(start 0.7874 0.4064)
			(end -0.7874 0.4064)
			(stroke
				(width 0.1524)
				(type default)
			)
			(layer "F.SilkS")
		)
		(fp_line
			(start 0.7874 -0.4064)
			(end 0.7874 0.4064)
			(stroke
				(width 0.1524)
				(type default)
			)
			(layer "F.SilkS")
		)
		(fp_line
			(start -0.7874 0.4064)
			(end -0.7874 -0.4064)
			(stroke
				(width 0.1524)
				(type default)
			)
			(layer "F.SilkS")
		)
		(fp_line
			(start -0.7874 -0.4064)
			(end 0.7874 -0.4064)
			(stroke
				(width 0.1524)
				(type default)
			)
			(layer "F.SilkS")
		)
		(fp_line
			(start 0.67945 0.3048)
			(end 0.120396 0.3048)
			(stroke
				(width 0.1)
				(type default)
			)
			(layer "F.Fab")
		)
		(fp_line
			(start 0.67945 -0.3048)
			(end 0.67945 0.3048)
			(stroke
				(width 0.1)
				(type default)
			)
			(layer "F.Fab")
		)
		(fp_line
			(start 0.12065 -0.2794)
			(end 0.12065 -0.3048)
			(stroke
				(width 0.1)
				(type default)
			)
			(layer "F.Fab")
		)
		(fp_line
			(start 0.12065 -0.3048)
			(end 0.67945 -0.3048)
			(stroke
				(width 0.1)
				(type default)
			)
			(layer "F.Fab")
		)
		(fp_line
			(start 0.120396 0.3048)
			(end 0.120396 0.2794)
			(stroke
				(width 0.1)
				(type default)
			)
			(layer "F.Fab")
		)
		(fp_line
			(start 0.120396 0.2794)
			(end -0.12065 0.2794)
			(stroke
				(width 0.1)
				(type default)
			)
			(layer "F.Fab")
		)
		(fp_line
			(start -0.12065 0.3048)
			(end -0.67945 0.3048)
			(stroke
				(width 0.1)
				(type default)
			)
			(layer "F.Fab")
		)
		(fp_line
			(start -0.12065 0.2794)
			(end -0.12065 0.3048)
			(stroke
				(width 0.1)
				(type default)
			)
			(layer "F.Fab")
		)
		(fp_line
			(start -0.12065 -0.2794)
			(end 0.12065 -0.2794)
			(stroke
				(width 0.1)
				(type default)
			)
			(layer "F.Fab")
		)
		(fp_line
			(start -0.12065 -0.305054)
			(end -0.12065 -0.2794)
			(stroke
				(width 0.1)
				(type default)
			)
			(layer "F.Fab")
		)
		(fp_line
			(start -0.67945 0.3048)
			(end -0.67945 -0.305054)
			(stroke
				(width 0.1)
				(type default)
			)
			(layer "F.Fab")
		)
		(fp_line
			(start -0.67945 -0.305054)
			(end -0.12065 -0.305054)
			(stroke
				(width 0.1)
				(type default)
			)
			(layer "F.Fab")
		)
		(pad "1" smd circle
			(at -0.40005 0 180)
			(size 0 0)
			(layers "F.Cu" "F.Mask" "F.Paste")
			(net "FM_BIOS_POST_CMPLT_N")
		)
		(pad "2" smd circle
			(at 0.40005 0 180)
			(size 0 0)
			(layers "F.Cu" "F.Mask" "F.Paste")
			(net "FM_BIOS_POST_CMPLT_BMC_N")
		)
	)
	(footprint ""
		(layer "F.Cu")
		(at 325.605902 -20.548346 -90)
		(property "Reference" "R1487"
			(at 0 0 270)
			(layer "F.SilkS")
			(hide yes)
			(effects
				(font
					(size 1.27 1.27)
				)
			)
		)
		(property "Value" ""
			(at 0 0 270)
			(layer "F.Fab")
			(effects
				(font
					(size 1.27 1.27)
				)
			)
		)
		(duplicate_pad_numbers_are_jumpers no)
		(fp_line
			(start -0.7874 0.4064)
			(end -0.7874 -0.4064)
			(stroke
				(width 0.1524)
				(type default)
			)
			(layer "F.SilkS")
		)
		(fp_line
			(start 0.7874 0.4064)
			(end -0.7874 0.4064)
			(stroke
				(width 0.1524)
				(type default)
			)
			(layer "F.SilkS")
		)
		(fp_line
			(start -0.7874 -0.4064)
			(end 0.7874 -0.4064)
			(stroke
				(width 0.1524)
				(type default)
			)
			(layer "F.SilkS")
		)
		(fp_line
			(start 0.7874 -0.4064)
			(end 0.7874 0.4064)
			(stroke
				(width 0.1524)
				(type default)
			)
			(layer "F.SilkS")
		)
		(fp_line
			(start -0.67945 0.3048)
			(end -0.67945 -0.305054)
			(stroke
				(width 0.1)
				(type default)
			)
			(layer "F.Fab")
		)
		(fp_line
			(start -0.12065 0.3048)
			(end -0.67945 0.3048)
			(stroke
				(width 0.1)
				(type default)
			)
			(layer "F.Fab")
		)
		(fp_line
			(start 0.120396 0.3048)
			(end 0.120396 0.2794)
			(stroke
				(width 0.1)
				(type default)
			)
			(layer "F.Fab")
		)
		(fp_line
			(start 0.67945 0.3048)
			(end 0.120396 0.3048)
			(stroke
				(width 0.1)
				(type default)
			)
			(layer "F.Fab")
		)
		(fp_line
			(start -0.12065 0.2794)
			(end -0.12065 0.3048)
			(stroke
				(width 0.1)
				(type default)
			)
			(layer "F.Fab")
		)
		(fp_line
			(start 0.120396 0.2794)
			(end -0.12065 0.2794)
			(stroke
				(width 0.1)
				(type default)
			)
			(layer "F.Fab")
		)
		(fp_line
			(start -0.12065 -0.2794)
			(end 0.12065 -0.2794)
			(stroke
				(width 0.1)
				(type default)
			)
			(layer "F.Fab")
		)
		(fp_line
			(start 0.12065 -0.2794)
			(end 0.12065 -0.3048)
			(stroke
				(width 0.1)
				(type default)
			)
			(layer "F.Fab")
		)
		(fp_line
			(start 0.12065 -0.3048)
			(end 0.67945 -0.3048)
			(stroke
				(width 0.1)
				(type default)
			)
			(layer "F.Fab")
		)
		(fp_line
			(start 0.67945 -0.3048)
			(end 0.67945 0.3048)
			(stroke
				(width 0.1)
				(type default)
			)
			(layer "F.Fab")
		)
		(fp_line
			(start -0.67945 -0.305054)
			(end -0.12065 -0.305054)
			(stroke
				(width 0.1)
				(type default)
			)
			(layer "F.Fab")
		)
		(fp_line
			(start -0.12065 -0.305054)
			(end -0.12065 -0.2794)
			(stroke
				(width 0.1)
				(type default)
			)
			(layer "F.Fab")
		)
		(pad "1" smd circle
			(at -0.40005 0 270)
			(size 0 0)
			(layers "F.Cu" "F.Mask" "F.Paste")
			(net "FM_PCH_SATA_RAID_KEY")
		)
		(pad "2" smd circle
			(at 0.40005 0 270)
			(size 0 0)
			(layers "F.Cu" "F.Mask" "F.Paste")
			(net "GND")
		)
	)
	(footprint ""
		(layer "F.Cu")
		(at 312.341768 -408.517344 -90)
		(property "Reference" "C907"
			(at 0 0 270)
			(layer "F.SilkS")
			(hide yes)
			(effects
				(font
					(size 1.27 1.27)
				)
			)
		)
		(property "Value" ""
			(at 0 0 270)
			(layer "F.Fab")
			(effects
				(font
					(size 1.27 1.27)
				)
			)
		)
		(duplicate_pad_numbers_are_jumpers no)
		(fp_line
			(start -0.299974 0.150114)
			(end -0.299974 -0.150114)
			(stroke
				(width 0.1)
				(type default)
			)
			(layer "F.Fab")
		)
		(fp_line
			(start 0.299974 0.150114)
			(end -0.299974 0.150114)
			(stroke
				(width 0.1)
				(type default)
			)
			(layer "F.Fab")
		)
		(fp_line
			(start -0.299974 -0.150114)
			(end 0.299974 -0.150114)
			(stroke
				(width 0.1)
				(type default)
			)
			(layer "F.Fab")
		)
		(fp_line
			(start 0.299974 -0.150114)
			(end 0.299974 0.150114)
			(stroke
				(width 0.1)
				(type default)
			)
			(layer "F.Fab")
		)
		(pad "1" smd rect
			(at -0.2667 0 270)
			(size 0.3048 0.381)
			(layers "F.Cu" "F.Mask" "F.Paste")
			(net "P5E_CPU0_PE0_TX_C_DP<13>")
		)
		(pad "2" smd rect
			(at 0.2667 0 270)
			(size 0.3048 0.381)
			(layers "F.Cu" "F.Mask" "F.Paste")
			(net "P5E_CPU0_PE0_TX_DP<13>")
		)
	)
)
